(kicad_pcb
	(version 20260206)
	(generator "pcbnew")
	(generator_version "10.0")
	(general
		(thickness 1.6)
		(legacy_teardrops no)
	)
	(paper "A4")
	(title_block
		(title "Wiwynn_Tioga_Pass_MB.brd")
		(comment 1 "Tioga Pass / footprints 3025-3032 of 4770")
	)
	(layers
		(0 "F.Cu" signal "TOP")
		(4 "In1.Cu" signal "L2GND")
		(6 "In2.Cu" signal "L3")
		(8 "In3.Cu" signal "L4GND")
		(10 "In4.Cu" signal "L5")
		(12 "In5.Cu" signal "L6GND")
		(14 "In6.Cu" signal "L7VCC")
		(16 "In7.Cu" signal "L8VCC")
		(18 "In8.Cu" signal "L9GND")
		(20 "In9.Cu" signal "L10")
		(22 "In10.Cu" signal "L11GND")
		(24 "In11.Cu" signal "L12")
		(26 "In12.Cu" signal "L13GND")
		(2 "B.Cu" signal "BOTTOM")
		(9 "F.Adhes" user "F.Adhesive")
		(11 "B.Adhes" user "B.Adhesive")
		(13 "F.Paste" user "Package Geometry/Pastemask Top")
		(15 "B.Paste" user "Package Geometry/Pastemask Bottom")
		(5 "F.SilkS" user "Ref Des/Silkscreen Top")
		(7 "B.SilkS" user "Ref Des/Silkscreen Bottom")
		(1 "F.Mask" user "Board Geometry/Soldermask Top")
		(3 "B.Mask" user "Board Geometry/Soldermask Bottom")
		(17 "Dwgs.User" user "User.Drawings")
		(19 "Cmts.User" user "User.Comments")
		(21 "Eco1.User" user "User.Eco1")
		(23 "Eco2.User" user "User.Eco2")
		(25 "Edge.Cuts" user "Board Geometry/Outline")
		(27 "Margin" user)
		(31 "F.CrtYd" user "Package Geometry/Place Bound Top")
		(29 "B.CrtYd" user "Package Geometry/Place Bound Bottom")
		(35 "F.Fab" user "Ref Des/Assembly Top")
		(33 "B.Fab" user "Ref Des/Assembly Bottom")
	)
	(footprint ""
		(layer "B.Cu")
		(at 441.833 -13.1064 90)
		(property "Reference" "R1U37"
			(at 0 0 90)
			(layer "B.SilkS")
			(hide yes)
			(effects
				(font
					(size 1.27 1.27)
				)
				(justify mirror)
			)
		)
		(property "Value" ""
			(at 0 0 90)
			(layer "B.Fab")
			(effects
				(font
					(size 1.27 1.27)
				)
				(justify mirror)
			)
		)
		(duplicate_pad_numbers_are_jumpers no)
		(fp_poly
			(pts
				(xy 0.2794 -0.1016) (xy -0.2794 -0.1016) (xy -0.2794 0.9906) (xy 0.2794 0.9906)
			)
			(stroke
				(width 0)
				(type default)
			)
			(fill no)
			(layer "B.CrtYd")
		)
		(fp_line
			(start 0.2794 -0.1016)
			(end 0.2794 0.9906)
			(stroke
				(width 0.1)
				(type default)
			)
			(layer "B.Fab")
		)
		(fp_line
			(start -0.2794 -0.1016)
			(end 0.2794 -0.1016)
			(stroke
				(width 0.1)
				(type default)
			)
			(layer "B.Fab")
		)
		(fp_line
			(start 0.2794 0.9906)
			(end -0.2794 0.9906)
			(stroke
				(width 0.1)
				(type default)
			)
			(layer "B.Fab")
		)
		(fp_line
			(start -0.2794 0.9906)
			(end -0.2794 -0.1016)
			(stroke
				(width 0.1)
				(type default)
			)
			(layer "B.Fab")
		)
		(pad "1" smd rect
			(at 0 0 270)
			(size 0.508 0.508)
			(layers "B.Cu" "B.Mask" "B.Paste")
			(net "P0V7_GTL2014_2")
		)
		(pad "2" smd rect
			(at 0 0.889 270)
			(size 0.508 0.508)
			(layers "B.Cu" "B.Mask" "B.Paste")
			(net "GND")
		)
		(zone
			(layer "B.Cu")
			(hatch none 0.5)
			(connect_pads
				(clearance 0)
			)
			(min_thickness 0.25)
			(keepout
				(tracks allowed)
				(vias not_allowed)
				(pads allowed)
				(copperpour not_allowed)
				(footprints allowed)
			)
			(placement
				(enabled no)
				(sheetname "")
			)
			(fill
				(thermal_gap 0.5)
				(thermal_bridge_width 0.5)
				(island_removal_mode 0)
			)
			(polygon
				(pts
					(xy 442.087 -13.3604) (xy 442.087 -12.8524) (xy 442.468 -12.8524) (xy 442.468 -13.3604)
				)
			)
		)
		(zone
			(layer "B.Cu")
			(hatch none 0.5)
			(connect_pads
				(clearance 0)
			)
			(min_thickness 0.25)
			(keepout
				(tracks not_allowed)
				(vias allowed)
				(pads allowed)
				(copperpour not_allowed)
				(footprints allowed)
			)
			(placement
				(enabled no)
				(sheetname "")
			)
			(fill
				(thermal_gap 0.5)
				(thermal_bridge_width 0.5)
				(island_removal_mode 0)
			)
			(polygon
				(pts
					(xy 442.468 -13.3604) (xy 442.468 -12.8524) (xy 442.087 -12.8524) (xy 442.087 -13.3604)
				)
			)
		)
	)
	(footprint ""
		(layer "B.Cu")
		(at 411.4165 -4.318 -90)
		(property "Reference" "C8D4"
			(at 0 0 90)
			(layer "B.SilkS")
			(hide yes)
			(effects
				(font
					(size 1.27 1.27)
				)
				(justify mirror)
			)
		)
		(property "Value" ""
			(at 0 0 90)
			(layer "B.Fab")
			(effects
				(font
					(size 1.27 1.27)
				)
				(justify mirror)
			)
		)
		(duplicate_pad_numbers_are_jumpers no)
		(fp_poly
			(pts
				(xy -0.3048 -0.1016) (xy -0.3048 0.9906) (xy 0.3048 0.9906) (xy 0.3048 -0.1016)
			)
			(stroke
				(width 0)
				(type default)
			)
			(fill no)
			(layer "B.CrtYd")
		)
		(fp_line
			(start -0.3048 0.9906)
			(end -0.3048 -0.1016)
			(stroke
				(width 0.1)
				(type default)
			)
			(layer "B.Fab")
		)
		(fp_line
			(start 0.3048 0.9906)
			(end -0.3048 0.9906)
			(stroke
				(width 0.1)
				(type default)
			)
			(layer "B.Fab")
		)
		(fp_line
			(start -0.3048 -0.1016)
			(end 0.3048 -0.1016)
			(stroke
				(width 0.1)
				(type default)
			)
			(layer "B.Fab")
		)
		(fp_line
			(start 0.3048 -0.1016)
			(end 0.3048 0.9906)
			(stroke
				(width 0.1)
				(type default)
			)
			(layer "B.Fab")
		)
		(pad "1" smd rect
			(at 0 0 90)
			(size 0.508 0.508)
			(layers "B.Cu" "B.Mask" "B.Paste")
			(net "P3V3_STBY")
		)
		(pad "2" smd rect
			(at 0 0.889 90)
			(size 0.508 0.508)
			(layers "B.Cu" "B.Mask" "B.Paste")
			(net "GND")
		)
		(zone
			(layer "B.Cu")
			(hatch none 0.5)
			(connect_pads
				(clearance 0)
			)
			(min_thickness 0.25)
			(keepout
				(tracks not_allowed)
				(vias allowed)
				(pads allowed)
				(copperpour not_allowed)
				(footprints allowed)
			)
			(placement
				(enabled no)
				(sheetname "")
			)
			(fill
				(thermal_gap 0.5)
				(thermal_bridge_width 0.5)
				(island_removal_mode 0)
			)
			(polygon
				(pts
					(xy 410.7815 -4.064) (xy 410.7815 -4.572) (xy 411.1625 -4.572) (xy 411.1625 -4.064)
				)
			)
		)
		(zone
			(layer "B.Cu")
			(hatch none 0.5)
			(connect_pads
				(clearance 0)
			)
			(min_thickness 0.25)
			(keepout
				(tracks allowed)
				(vias not_allowed)
				(pads allowed)
				(copperpour not_allowed)
				(footprints allowed)
			)
			(placement
				(enabled no)
				(sheetname "")
			)
			(fill
				(thermal_gap 0.5)
				(thermal_bridge_width 0.5)
				(island_removal_mode 0)
			)
			(polygon
				(pts
					(xy 411.1625 -4.064) (xy 411.1625 -4.572) (xy 410.7815 -4.572) (xy 410.7815 -4.064)
				)
			)
		)
	)
	(footprint ""
		(layer "B.Cu")
		(at 461.277208 -147.650454 90)
		(property "Reference" "R1L15"
			(at 0 0 90)
			(layer "B.SilkS")
			(hide yes)
			(effects
				(font
					(size 1.27 1.27)
				)
				(justify mirror)
			)
		)
		(property "Value" ""
			(at 0 0 90)
			(layer "B.Fab")
			(effects
				(font
					(size 1.27 1.27)
				)
				(justify mirror)
			)
		)
		(duplicate_pad_numbers_are_jumpers no)
		(fp_poly
			(pts
				(xy 0.2794 -0.1016) (xy -0.2794 -0.1016) (xy -0.2794 0.9906) (xy 0.2794 0.9906)
			)
			(stroke
				(width 0)
				(type default)
			)
			(fill no)
			(layer "B.CrtYd")
		)
		(fp_line
			(start 0.2794 -0.1016)
			(end 0.2794 0.9906)
			(stroke
				(width 0.1)
				(type default)
			)
			(layer "B.Fab")
		)
		(fp_line
			(start -0.2794 -0.1016)
			(end 0.2794 -0.1016)
			(stroke
				(width 0.1)
				(type default)
			)
			(layer "B.Fab")
		)
		(fp_line
			(start 0.2794 0.9906)
			(end -0.2794 0.9906)
			(stroke
				(width 0.1)
				(type default)
			)
			(layer "B.Fab")
		)
		(fp_line
			(start -0.2794 0.9906)
			(end -0.2794 -0.1016)
			(stroke
				(width 0.1)
				(type default)
			)
			(layer "B.Fab")
		)
		(pad "1" smd rect
			(at 0 0 270)
			(size 0.508 0.508)
			(layers "B.Cu" "B.Mask" "B.Paste")
			(net "PVCCIO_CPU0")
		)
		(pad "2" smd rect
			(at 0 0.889 270)
			(size 0.508 0.508)
			(layers "B.Cu" "B.Mask" "B.Paste")
			(net "XDP_CPU_TMS")
		)
		(zone
			(layer "B.Cu")
			(hatch none 0.5)
			(connect_pads
				(clearance 0)
			)
			(min_thickness 0.25)
			(keepout
				(tracks allowed)
				(vias not_allowed)
				(pads allowed)
				(copperpour not_allowed)
				(footprints allowed)
			)
			(placement
				(enabled no)
				(sheetname "")
			)
			(fill
				(thermal_gap 0.5)
				(thermal_bridge_width 0.5)
				(island_removal_mode 0)
			)
			(polygon
				(pts
					(xy 461.531208 -147.904454) (xy 461.531208 -147.396454) (xy 461.912208 -147.396454) (xy 461.912208 -147.904454)
				)
			)
		)
		(zone
			(layer "B.Cu")
			(hatch none 0.5)
			(connect_pads
				(clearance 0)
			)
			(min_thickness 0.25)
			(keepout
				(tracks not_allowed)
				(vias allowed)
				(pads allowed)
				(copperpour not_allowed)
				(footprints allowed)
			)
			(placement
				(enabled no)
				(sheetname "")
			)
			(fill
				(thermal_gap 0.5)
				(thermal_bridge_width 0.5)
				(island_removal_mode 0)
			)
			(polygon
				(pts
					(xy 461.912208 -147.904454) (xy 461.912208 -147.396454) (xy 461.531208 -147.396454) (xy 461.531208 -147.904454)
				)
			)
		)
	)
	(footprint ""
		(layer "B.Cu")
		(at -3.1242 -6.4008 -90)
		(property "Reference" "C22W2"
			(at 0 0 90)
			(layer "B.SilkS")
			(hide yes)
			(effects
				(font
					(size 1.27 1.27)
				)
				(justify mirror)
			)
		)
		(property "Value" "*"
			(at 0.0762 -6.2357 270)
			(unlocked yes)
			(layer "B.Fab")
			(hide yes)
			(effects
				(font
					(size 1.27 1.016)
					(thickness 0.1524)
				)
				(justify mirror)
			)
		)
		(property "Device Type" "SC22U16V5MX-4-GP_SMD-BCG5-SC22A"
			(at 0.0762 -8.2677 270)
			(unlocked yes)
			(layer "B.Fab")
			(hide yes)
			(effects
				(font
					(size 1.27 1.016)
					(thickness 0.1524)
				)
				(justify mirror)
			)
		)
		(duplicate_pad_numbers_are_jumpers no)
		(fp_line
			(start -0.635 0)
			(end 0.635 0)
			(stroke
				(width 0.508)
				(type default)
			)
			(layer "B.SilkS")
		)
		(fp_rect
			(start 0.9652 1.778)
			(end -0.9652 -1.778)
			(stroke
				(width 0)
				(type default)
			)
			(fill no)
			(layer "B.CrtYd")
		)
		(fp_poly
			(pts
				(xy 0.9652 -1.778) (xy -0.9652 -1.778) (xy -0.9652 1.778) (xy 0.9652 1.778)
			)
			(stroke
				(width 0)
				(type default)
			)
			(fill no)
			(layer "B.Fab")
		)
		(pad "1" smd rect
			(at 0 -0.9652 90)
			(size 1.397 1.143)
			(layers "B.Cu" "B.Mask" "B.Paste")
			(net "VR_FET_SW_P12V_STBY_PVDDQ_GHJ")
		)
		(pad "2" smd rect
			(at 0 0.9652 90)
			(size 1.397 1.143)
			(layers "B.Cu" "B.Mask" "B.Paste")
			(net "GND")
		)
	)
	(footprint ""
		(layer "B.Cu")
		(at 111.094012 -29.94152 -90)
		(property "Reference" "SH7U1"
			(at 0 0 90)
			(layer "B.SilkS")
			(hide yes)
			(effects
				(font
					(size 1.27 1.27)
				)
				(justify mirror)
			)
		)
		(property "Value" ""
			(at 0 0 90)
			(layer "B.Fab")
			(effects
				(font
					(size 1.27 1.27)
				)
				(justify mirror)
			)
		)
		(duplicate_pad_numbers_are_jumpers no)
		(fp_poly
			(pts
				(xy 0.1651 -0.0508) (xy 0.1651 0.5842) (xy -0.1651 0.5842) (xy -0.1651 -0.0508)
			)
			(stroke
				(width 0)
				(type default)
			)
			(fill no)
			(layer "B.CrtYd")
		)
		(fp_line
			(start -0.1651 0.5842)
			(end 0.1651 0.5842)
			(stroke
				(width 0.1)
				(type default)
			)
			(layer "B.Fab")
		)
		(fp_line
			(start 0.1651 0.5842)
			(end 0.1651 -0.0508)
			(stroke
				(width 0.1)
				(type default)
			)
			(layer "B.Fab")
		)
		(fp_line
			(start -0.1651 -0.0508)
			(end -0.1651 0.5842)
			(stroke
				(width 0.1)
				(type default)
			)
			(layer "B.Fab")
		)
		(fp_line
			(start 0.1651 -0.0508)
			(end -0.1651 -0.0508)
			(stroke
				(width 0.1)
				(type default)
			)
			(layer "B.Fab")
		)
		(pad "1" smd custom
			(at 0 0 270)
			(size 0.0762 0.0762)
			(layers "B.Cu" "B.Mask" "B.Paste")
			(net "VSENSE_PVDDQ_GHJ_P")
			(options
				(clearance outline)
				(anchor circle)
			)
			(primitives
				(gr_poly
					(pts
						(arc
							(start -0.1524 0.10795)
							(mid -0.098518 0.130268)
							(end -0.0762 0.18415)
						)
						(xy -0.0762 0.22225) (xy 0.0762 0.22225)
						(arc
							(start 0.0762 0.18415)
							(mid 0.098518 0.130268)
							(end 0.1524 0.10795)
						)
						(xy 0.1524 -0.22225) (xy -0.1524 -0.22225)
					)
					(width 0)
					(fill yes)
				)
			)
		)
		(pad "2" smd custom
			(at 0 0.5334 90)
			(size 0.0762 0.0762)
			(layers "B.Cu" "B.Mask" "B.Paste")
			(net "PVDDQ_GHJ")
			(options
				(clearance outline)
				(anchor circle)
			)
			(primitives
				(gr_poly
					(pts
						(arc
							(start -0.1524 0.10795)
							(mid -0.098518 0.130268)
							(end -0.0762 0.18415)
						)
						(xy -0.0762 0.22225) (xy 0.0762 0.22225)
						(arc
							(start 0.0762 0.18415)
							(mid 0.098518 0.130268)
							(end 0.1524 0.10795)
						)
						(xy 0.1524 -0.22225) (xy -0.1524 -0.22225)
					)
					(width 0)
					(fill yes)
				)
			)
		)
	)
	(footprint ""
		(layer "B.Cu")
		(at 378.46 -83.4644 180)
		(property "Reference" "R7W3"
			(at 0.8382 -0.67818 180)
			(unlocked yes)
			(layer "B.SilkS")
			(effects
				(font
					(size 0.4064 0.254)
					(thickness 0.1524)
				)
				(justify left mirror)
			)
		)
		(property "Value" ""
			(at 0 0 0)
			(layer "B.Fab")
			(effects
				(font
					(size 1.27 1.27)
				)
				(justify mirror)
			)
		)
		(duplicate_pad_numbers_are_jumpers no)
		(fp_poly
			(pts
				(xy 0.2794 -0.1016) (xy -0.2794 -0.1016) (xy -0.2794 0.9906) (xy 0.2794 0.9906)
			)
			(stroke
				(width 0)
				(type default)
			)
			(fill no)
			(layer "B.CrtYd")
		)
		(fp_line
			(start 0.2794 0.9906)
			(end -0.2794 0.9906)
			(stroke
				(width 0.1)
				(type default)
			)
			(layer "B.Fab")
		)
		(fp_line
			(start 0.2794 -0.1016)
			(end 0.2794 0.9906)
			(stroke
				(width 0.1)
				(type default)
			)
			(layer "B.Fab")
		)
		(fp_line
			(start -0.2794 0.9906)
			(end -0.2794 -0.1016)
			(stroke
				(width 0.1)
				(type default)
			)
			(layer "B.Fab")
		)
		(fp_line
			(start -0.2794 -0.1016)
			(end 0.2794 -0.1016)
			(stroke
				(width 0.1)
				(type default)
			)
			(layer "B.Fab")
		)
		(pad "1" smd rect
			(at 0 0)
			(size 0.508 0.508)
			(layers "B.Cu" "B.Mask" "B.Paste")
			(net "P3V3_STBY")
		)
		(pad "2" smd rect
			(at 0 0.889)
			(size 0.508 0.508)
			(layers "B.Cu" "B.Mask" "B.Paste")
			(net "PECI_SEL")
		)
		(zone
			(layer "B.Cu")
			(hatch none 0.5)
			(connect_pads
				(clearance 0)
			)
			(min_thickness 0.25)
			(keepout
				(tracks not_allowed)
				(vias allowed)
				(pads allowed)
				(copperpour not_allowed)
				(footprints allowed)
			)
			(placement
				(enabled no)
				(sheetname "")
			)
			(fill
				(thermal_gap 0.5)
				(thermal_bridge_width 0.5)
				(island_removal_mode 0)
			)
			(polygon
				(pts
					(xy 378.206 -84.0994) (xy 378.714 -84.0994) (xy 378.714 -83.7184) (xy 378.206 -83.7184)
				)
			)
		)
		(zone
			(layer "B.Cu")
			(hatch none 0.5)
			(connect_pads
				(clearance 0)
			)
			(min_thickness 0.25)
			(keepout
				(tracks allowed)
				(vias not_allowed)
				(pads allowed)
				(copperpour not_allowed)
				(footprints allowed)
			)
			(placement
				(enabled no)
				(sheetname "")
			)
			(fill
				(thermal_gap 0.5)
				(thermal_bridge_width 0.5)
				(island_removal_mode 0)
			)
			(polygon
				(pts
					(xy 378.206 -83.7184) (xy 378.714 -83.7184) (xy 378.714 -84.0994) (xy 378.206 -84.0994)
				)
			)
		)
	)
	(footprint ""
		(layer "B.Cu")
		(at 407.86304 -56.15686 180)
		(property "Reference" "R1W4"
			(at 0.8382 -0.67818 180)
			(unlocked yes)
			(layer "B.SilkS")
			(effects
				(font
					(size 0.4064 0.254)
					(thickness 0.1524)
				)
				(justify left mirror)
			)
		)
		(property "Value" ""
			(at 0 0 0)
			(layer "B.Fab")
			(effects
				(font
					(size 1.27 1.27)
				)
				(justify mirror)
			)
		)
		(duplicate_pad_numbers_are_jumpers no)
		(fp_poly
			(pts
				(xy 0.2794 -0.1016) (xy -0.2794 -0.1016) (xy -0.2794 0.9906) (xy 0.2794 0.9906)
			)
			(stroke
				(width 0)
				(type default)
			)
			(fill no)
			(layer "B.CrtYd")
		)
		(fp_line
			(start 0.2794 0.9906)
			(end -0.2794 0.9906)
			(stroke
				(width 0.1)
				(type default)
			)
			(layer "B.Fab")
		)
		(fp_line
			(start 0.2794 -0.1016)
			(end 0.2794 0.9906)
			(stroke
				(width 0.1)
				(type default)
			)
			(layer "B.Fab")
		)
		(fp_line
			(start -0.2794 0.9906)
			(end -0.2794 -0.1016)
			(stroke
				(width 0.1)
				(type default)
			)
			(layer "B.Fab")
		)
		(fp_line
			(start -0.2794 -0.1016)
			(end 0.2794 -0.1016)
			(stroke
				(width 0.1)
				(type default)
			)
			(layer "B.Fab")
		)
		(pad "1" smd rect
			(at 0 0)
			(size 0.508 0.508)
			(layers "B.Cu" "B.Mask" "B.Paste")
			(net "FM_OCP_MEZZB_PRES_LVT3_BMC")
		)
		(pad "2" smd rect
			(at 0 0.889)
			(size 0.508 0.508)
			(layers "B.Cu" "B.Mask" "B.Paste")
			(net "P3V3_STBY")
		)
		(zone
			(layer "B.Cu")
			(hatch none 0.5)
			(connect_pads
				(clearance 0)
			)
			(min_thickness 0.25)
			(keepout
				(tracks not_allowed)
				(vias allowed)
				(pads allowed)
				(copperpour not_allowed)
				(footprints allowed)
			)
			(placement
				(enabled no)
				(sheetname "")
			)
			(fill
				(thermal_gap 0.5)
				(thermal_bridge_width 0.5)
				(island_removal_mode 0)
			)
			(polygon
				(pts
					(xy 407.60904 -56.79186) (xy 408.11704 -56.79186) (xy 408.11704 -56.41086) (xy 407.60904 -56.41086)
				)
			)
		)
		(zone
			(layer "B.Cu")
			(hatch none 0.5)
			(connect_pads
				(clearance 0)
			)
			(min_thickness 0.25)
			(keepout
				(tracks allowed)
				(vias not_allowed)
				(pads allowed)
				(copperpour not_allowed)
				(footprints allowed)
			)
			(placement
				(enabled no)
				(sheetname "")
			)
			(fill
				(thermal_gap 0.5)
				(thermal_bridge_width 0.5)
				(island_removal_mode 0)
			)
			(polygon
				(pts
					(xy 407.60904 -56.41086) (xy 408.11704 -56.41086) (xy 408.11704 -56.79186) (xy 407.60904 -56.79186)
				)
			)
		)
	)
	(footprint ""
		(layer "B.Cu")
		(at 403.568408 -93.755718 -90)
		(property "Reference" "R2N24"
			(at 0 0 90)
			(layer "B.SilkS")
			(hide yes)
			(effects
				(font
					(size 1.27 1.27)
				)
				(justify mirror)
			)
		)
		(property "Value" ""
			(at 0 0 90)
			(layer "B.Fab")
			(effects
				(font
					(size 1.27 1.27)
				)
				(justify mirror)
			)
		)
		(duplicate_pad_numbers_are_jumpers no)
		(fp_poly
			(pts
				(xy 0.2794 -0.1016) (xy -0.2794 -0.1016) (xy -0.2794 0.9906) (xy 0.2794 0.9906)
			)
			(stroke
				(width 0)
				(type default)
			)
			(fill no)
			(layer "B.CrtYd")
		)
		(fp_line
			(start -0.2794 0.9906)
			(end -0.2794 -0.1016)
			(stroke
				(width 0.1)
				(type default)
			)
			(layer "B.Fab")
		)
		(fp_line
			(start 0.2794 0.9906)
			(end -0.2794 0.9906)
			(stroke
				(width 0.1)
				(type default)
			)
			(layer "B.Fab")
		)
		(fp_line
			(start -0.2794 -0.1016)
			(end 0.2794 -0.1016)
			(stroke
				(width 0.1)
				(type default)
			)
			(layer "B.Fab")
		)
		(fp_line
			(start 0.2794 -0.1016)
			(end 0.2794 0.9906)
			(stroke
				(width 0.1)
				(type default)
			)
			(layer "B.Fab")
		)
		(pad "1" smd rect
			(at 0 0 90)
			(size 0.508 0.508)
			(layers "B.Cu" "B.Mask" "B.Paste")
			(net "FM_QAT_EN_N")
		)
		(pad "2" smd rect
			(at 0 0.889 90)
			(size 0.508 0.508)
			(layers "B.Cu" "B.Mask" "B.Paste")
			(net "GND")
		)
		(zone
			(layer "B.Cu")
			(hatch none 0.5)
			(connect_pads
				(clearance 0)
			)
			(min_thickness 0.25)
			(keepout
				(tracks not_allowed)
				(vias allowed)
				(pads allowed)
				(copperpour not_allowed)
				(footprints allowed)
			)
			(placement
				(enabled no)
				(sheetname "")
			)
			(fill
				(thermal_gap 0.5)
				(thermal_bridge_width 0.5)
				(island_removal_mode 0)
			)
			(polygon
				(pts
					(xy 402.933408 -93.501718) (xy 402.933408 -94.009718) (xy 403.314408 -94.009718) (xy 403.314408 -93.501718)
				)
			)
		)
		(zone
			(layer "B.Cu")
			(hatch none 0.5)
			(connect_pads
				(clearance 0)
			)
			(min_thickness 0.25)
			(keepout
				(tracks allowed)
				(vias not_allowed)
				(pads allowed)
				(copperpour not_allowed)
				(footprints allowed)
			)
			(placement
				(enabled no)
				(sheetname "")
			)
			(fill
				(thermal_gap 0.5)
				(thermal_bridge_width 0.5)
				(island_removal_mode 0)
			)
			(polygon
				(pts
					(xy 403.314408 -93.501718) (xy 403.314408 -94.009718) (xy 402.933408 -94.009718) (xy 402.933408 -93.501718)
				)
			)
		)
	)
)
